(kicad_pcb
	(version 20260206)
	(generator "pcbnew")
	(generator_version "10.0")
	(general
		(thickness 1.6)
		(legacy_teardrops no)
	)
	(paper "A4")
	(title_block
		(title "04192023_DAF0TMB3IC0_F0TG_MB_C_brd_V02_OCP.brd")
		(comment 1 "Grand Teton / footprints 6000-6006 of 8354")
	)
	(layers
		(0 "F.Cu" signal "TOP")
		(4 "In1.Cu" signal "GND")
		(6 "In2.Cu" signal "IN1")
		(8 "In3.Cu" signal "GND1")
		(10 "In4.Cu" signal "IN2")
		(12 "In5.Cu" signal "GND2")
		(14 "In6.Cu" signal "IN3")
		(16 "In7.Cu" signal "GND3")
		(18 "In8.Cu" signal "VCC")
		(20 "In9.Cu" signal "VCC1")
		(22 "In10.Cu" signal "GND4")
		(24 "In11.Cu" signal "IN4")
		(26 "In12.Cu" signal "GND5")
		(28 "In13.Cu" signal "IN5")
		(30 "In14.Cu" signal "GND6")
		(32 "In15.Cu" signal "IN6")
		(34 "In16.Cu" signal "GND7")
		(2 "B.Cu" signal "BOTTOM")
		(9 "F.Adhes" user "F.Adhesive")
		(11 "B.Adhes" user "B.Adhesive")
		(13 "F.Paste" user "Package Geometry/Pastemask Top")
		(15 "B.Paste" user "Package Geometry/Pastemask Bottom")
		(5 "F.SilkS" user "Ref Des/Silkscreen Top")
		(7 "B.SilkS" user "Ref Des/Silkscreen Bottom")
		(1 "F.Mask" user "Board Geometry/Soldermask Top")
		(3 "B.Mask" user "Board Geometry/Soldermask Bottom")
		(17 "Dwgs.User" user "User.Drawings")
		(19 "Cmts.User" user "User.Comments")
		(21 "Eco1.User" user "User.Eco1")
		(23 "Eco2.User" user "User.Eco2")
		(25 "Edge.Cuts" user "Board Geometry/Outline")
		(27 "Margin" user)
		(31 "F.CrtYd" user "Package Geometry/Place Bound Top")
		(29 "B.CrtYd" user "Package Geometry/Place Bound Bottom")
		(35 "F.Fab" user "Ref Des/Assembly Top")
		(33 "B.Fab" user "Ref Des/Assembly Bottom")
	)
	(footprint ""
		(layer "B.Cu")
		(at 104.648 -415.925 90)
		(property "Reference" "R4543"
			(at 0 0 90)
			(layer "B.SilkS")
			(hide yes)
			(effects
				(font
					(size 1.27 1.27)
				)
				(justify mirror)
			)
		)
		(property "Value" ""
			(at 0 0 90)
			(layer "B.Fab")
			(effects
				(font
					(size 1.27 1.27)
				)
				(justify mirror)
			)
		)
		(duplicate_pad_numbers_are_jumpers no)
		(fp_line
			(start 0.7874 -0.4064)
			(end -0.7874 -0.4064)
			(stroke
				(width 0.1524)
				(type default)
			)
			(layer "B.SilkS")
		)
		(fp_line
			(start -0.7874 -0.4064)
			(end -0.7874 0.4064)
			(stroke
				(width 0.1524)
				(type default)
			)
			(layer "B.SilkS")
		)
		(fp_line
			(start 0.7874 0.4064)
			(end 0.7874 -0.4064)
			(stroke
				(width 0.1524)
				(type default)
			)
			(layer "B.SilkS")
		)
		(fp_line
			(start -0.7874 0.4064)
			(end 0.7874 0.4064)
			(stroke
				(width 0.1524)
				(type default)
			)
			(layer "B.SilkS")
		)
		(fp_line
			(start 0.67945 -0.305054)
			(end 0.12065 -0.305054)
			(stroke
				(width 0.1)
				(type default)
			)
			(layer "B.Fab")
		)
		(fp_line
			(start 0.12065 -0.305054)
			(end 0.12065 -0.2794)
			(stroke
				(width 0.1)
				(type default)
			)
			(layer "B.Fab")
		)
		(fp_line
			(start -0.12065 -0.3048)
			(end -0.67945 -0.3048)
			(stroke
				(width 0.1)
				(type default)
			)
			(layer "B.Fab")
		)
		(fp_line
			(start -0.67945 -0.3048)
			(end -0.67945 0.3048)
			(stroke
				(width 0.1)
				(type default)
			)
			(layer "B.Fab")
		)
		(fp_line
			(start 0.12065 -0.2794)
			(end -0.12065 -0.2794)
			(stroke
				(width 0.1)
				(type default)
			)
			(layer "B.Fab")
		)
		(fp_line
			(start -0.12065 -0.2794)
			(end -0.12065 -0.3048)
			(stroke
				(width 0.1)
				(type default)
			)
			(layer "B.Fab")
		)
		(fp_line
			(start 0.12065 0.2794)
			(end 0.12065 0.3048)
			(stroke
				(width 0.1)
				(type default)
			)
			(layer "B.Fab")
		)
		(fp_line
			(start -0.120396 0.2794)
			(end 0.12065 0.2794)
			(stroke
				(width 0.1)
				(type default)
			)
			(layer "B.Fab")
		)
		(fp_line
			(start 0.67945 0.3048)
			(end 0.67945 -0.305054)
			(stroke
				(width 0.1)
				(type default)
			)
			(layer "B.Fab")
		)
		(fp_line
			(start 0.12065 0.3048)
			(end 0.67945 0.3048)
			(stroke
				(width 0.1)
				(type default)
			)
			(layer "B.Fab")
		)
		(fp_line
			(start -0.120396 0.3048)
			(end -0.120396 0.2794)
			(stroke
				(width 0.1)
				(type default)
			)
			(layer "B.Fab")
		)
		(fp_line
			(start -0.67945 0.3048)
			(end -0.120396 0.3048)
			(stroke
				(width 0.1)
				(type default)
			)
			(layer "B.Fab")
		)
		(pad "1" smd circle
			(at 0.40005 0 270)
			(size 0 0)
			(layers "B.Cu" "B.Mask" "B.Paste")
			(net "P3V3_AUX")
		)
		(pad "2" smd circle
			(at -0.40005 0 270)
			(size 0 0)
			(layers "B.Cu" "B.Mask" "B.Paste")
			(net "HGX_DETECT_N")
		)
	)
	(footprint ""
		(layer "B.Cu")
		(at 353.900232 -255.554988 180)
		(property "Reference" "C2526"
			(at 0 0 0)
			(layer "B.SilkS")
			(hide yes)
			(effects
				(font
					(size 1.27 1.27)
				)
				(justify mirror)
			)
		)
		(property "Value" ""
			(at 0 0 0)
			(layer "B.Fab")
			(effects
				(font
					(size 1.27 1.27)
				)
				(justify mirror)
			)
		)
		(duplicate_pad_numbers_are_jumpers no)
		(fp_line
			(start 0.7874 0.4064)
			(end 0.7874 -0.4064)
			(stroke
				(width 0.1524)
				(type default)
			)
			(layer "B.SilkS")
		)
		(fp_line
			(start 0.7874 -0.4064)
			(end -0.7874 -0.4064)
			(stroke
				(width 0.1524)
				(type default)
			)
			(layer "B.SilkS")
		)
		(fp_line
			(start -0.7874 0.4064)
			(end 0.7874 0.4064)
			(stroke
				(width 0.1524)
				(type default)
			)
			(layer "B.SilkS")
		)
		(fp_line
			(start -0.7874 -0.4064)
			(end -0.7874 0.4064)
			(stroke
				(width 0.1524)
				(type default)
			)
			(layer "B.SilkS")
		)
		(fp_line
			(start 0.67945 0.3048)
			(end 0.67945 -0.305054)
			(stroke
				(width 0.1)
				(type default)
			)
			(layer "B.Fab")
		)
		(fp_line
			(start 0.67945 -0.305054)
			(end 0.12065 -0.305054)
			(stroke
				(width 0.1)
				(type default)
			)
			(layer "B.Fab")
		)
		(fp_line
			(start 0.12065 0.3048)
			(end 0.67945 0.3048)
			(stroke
				(width 0.1)
				(type default)
			)
			(layer "B.Fab")
		)
		(fp_line
			(start 0.12065 0.2794)
			(end 0.12065 0.3048)
			(stroke
				(width 0.1)
				(type default)
			)
			(layer "B.Fab")
		)
		(fp_line
			(start 0.12065 -0.2794)
			(end -0.12065 -0.2794)
			(stroke
				(width 0.1)
				(type default)
			)
			(layer "B.Fab")
		)
		(fp_line
			(start 0.12065 -0.305054)
			(end 0.12065 -0.2794)
			(stroke
				(width 0.1)
				(type default)
			)
			(layer "B.Fab")
		)
		(fp_line
			(start -0.120396 0.3048)
			(end -0.120396 0.2794)
			(stroke
				(width 0.1)
				(type default)
			)
			(layer "B.Fab")
		)
		(fp_line
			(start -0.120396 0.2794)
			(end 0.12065 0.2794)
			(stroke
				(width 0.1)
				(type default)
			)
			(layer "B.Fab")
		)
		(fp_line
			(start -0.12065 -0.2794)
			(end -0.12065 -0.3048)
			(stroke
				(width 0.1)
				(type default)
			)
			(layer "B.Fab")
		)
		(fp_line
			(start -0.12065 -0.3048)
			(end -0.67945 -0.3048)
			(stroke
				(width 0.1)
				(type default)
			)
			(layer "B.Fab")
		)
		(fp_line
			(start -0.67945 0.3048)
			(end -0.120396 0.3048)
			(stroke
				(width 0.1)
				(type default)
			)
			(layer "B.Fab")
		)
		(fp_line
			(start -0.67945 -0.3048)
			(end -0.67945 0.3048)
			(stroke
				(width 0.1)
				(type default)
			)
			(layer "B.Fab")
		)
		(pad "1" smd circle
			(at 0.40005 0)
			(size 0 0)
			(layers "B.Cu" "B.Mask" "B.Paste")
			(net "PVDD18_S5_P0")
		)
		(pad "2" smd circle
			(at -0.40005 0)
			(size 0 0)
			(layers "B.Cu" "B.Mask" "B.Paste")
			(net "GND")
		)
	)
	(footprint ""
		(layer "B.Cu")
		(at 443.29985 -194.88531 180)
		(property "Reference" "R768"
			(at 0 0 0)
			(layer "B.SilkS")
			(hide yes)
			(effects
				(font
					(size 1.27 1.27)
				)
				(justify mirror)
			)
		)
		(property "Value" ""
			(at 0 0 0)
			(layer "B.Fab")
			(effects
				(font
					(size 1.27 1.27)
				)
				(justify mirror)
			)
		)
		(duplicate_pad_numbers_are_jumpers no)
		(fp_line
			(start 0.7874 0.4064)
			(end 0.7874 -0.4064)
			(stroke
				(width 0.1524)
				(type default)
			)
			(layer "B.SilkS")
		)
		(fp_line
			(start 0.7874 -0.4064)
			(end -0.7874 -0.4064)
			(stroke
				(width 0.1524)
				(type default)
			)
			(layer "B.SilkS")
		)
		(fp_line
			(start -0.7874 0.4064)
			(end 0.7874 0.4064)
			(stroke
				(width 0.1524)
				(type default)
			)
			(layer "B.SilkS")
		)
		(fp_line
			(start -0.7874 -0.4064)
			(end -0.7874 0.4064)
			(stroke
				(width 0.1524)
				(type default)
			)
			(layer "B.SilkS")
		)
		(fp_line
			(start 0.67945 0.3048)
			(end 0.67945 -0.305054)
			(stroke
				(width 0.1)
				(type default)
			)
			(layer "B.Fab")
		)
		(fp_line
			(start 0.67945 -0.305054)
			(end 0.12065 -0.305054)
			(stroke
				(width 0.1)
				(type default)
			)
			(layer "B.Fab")
		)
		(fp_line
			(start 0.12065 0.3048)
			(end 0.67945 0.3048)
			(stroke
				(width 0.1)
				(type default)
			)
			(layer "B.Fab")
		)
		(fp_line
			(start 0.12065 0.2794)
			(end 0.12065 0.3048)
			(stroke
				(width 0.1)
				(type default)
			)
			(layer "B.Fab")
		)
		(fp_line
			(start 0.12065 -0.2794)
			(end -0.12065 -0.2794)
			(stroke
				(width 0.1)
				(type default)
			)
			(layer "B.Fab")
		)
		(fp_line
			(start 0.12065 -0.305054)
			(end 0.12065 -0.2794)
			(stroke
				(width 0.1)
				(type default)
			)
			(layer "B.Fab")
		)
		(fp_line
			(start -0.120396 0.3048)
			(end -0.120396 0.2794)
			(stroke
				(width 0.1)
				(type default)
			)
			(layer "B.Fab")
		)
		(fp_line
			(start -0.120396 0.2794)
			(end 0.12065 0.2794)
			(stroke
				(width 0.1)
				(type default)
			)
			(layer "B.Fab")
		)
		(fp_line
			(start -0.12065 -0.2794)
			(end -0.12065 -0.3048)
			(stroke
				(width 0.1)
				(type default)
			)
			(layer "B.Fab")
		)
		(fp_line
			(start -0.12065 -0.3048)
			(end -0.67945 -0.3048)
			(stroke
				(width 0.1)
				(type default)
			)
			(layer "B.Fab")
		)
		(fp_line
			(start -0.67945 0.3048)
			(end -0.120396 0.3048)
			(stroke
				(width 0.1)
				(type default)
			)
			(layer "B.Fab")
		)
		(fp_line
			(start -0.67945 -0.3048)
			(end -0.67945 0.3048)
			(stroke
				(width 0.1)
				(type default)
			)
			(layer "B.Fab")
		)
		(pad "1" smd circle
			(at 0.40005 0)
			(size 0 0)
			(layers "B.Cu" "B.Mask" "B.Paste")
			(net "PD_CHK_CPU0_DIMM_SAA")
		)
		(pad "2" smd circle
			(at -0.40005 0)
			(size 0 0)
			(layers "B.Cu" "B.Mask" "B.Paste")
			(net "GND")
		)
	)
	(footprint ""
		(layer "B.Cu")
		(at 315.404246 -416.899344 90)
		(property "Reference" "C6539"
			(at 0 0 90)
			(layer "B.SilkS")
			(hide yes)
			(effects
				(font
					(size 1.27 1.27)
				)
				(justify mirror)
			)
		)
		(property "Value" ""
			(at 0 0 90)
			(layer "B.Fab")
			(effects
				(font
					(size 1.27 1.27)
				)
				(justify mirror)
			)
		)
		(duplicate_pad_numbers_are_jumpers no)
		(fp_line
			(start 0.299974 -0.150114)
			(end -0.299974 -0.150114)
			(stroke
				(width 0.1)
				(type default)
			)
			(layer "B.Fab")
		)
		(fp_line
			(start -0.299974 -0.150114)
			(end -0.299974 0.150114)
			(stroke
				(width 0.1)
				(type default)
			)
			(layer "B.Fab")
		)
		(fp_line
			(start 0.299974 0.150114)
			(end 0.299974 -0.150114)
			(stroke
				(width 0.1)
				(type default)
			)
			(layer "B.Fab")
		)
		(fp_line
			(start -0.299974 0.150114)
			(end 0.299974 0.150114)
			(stroke
				(width 0.1)
				(type default)
			)
			(layer "B.Fab")
		)
		(pad "1" smd rect
			(at 0.2667 0 270)
			(size 0.3048 0.381)
			(layers "B.Cu" "B.Mask" "B.Paste")
			(net "P5E_CPU0_P1_TX_BUF_C_DP<3>")
		)
		(pad "2" smd rect
			(at -0.2667 0 270)
			(size 0.3048 0.381)
			(layers "B.Cu" "B.Mask" "B.Paste")
			(net "P5E_CPU0_P1_TX_BUF_DP<3>")
		)
	)
	(footprint ""
		(layer "B.Cu")
		(at 190.404496 -193.996564)
		(property "Reference" "C172"
			(at 0 0 0)
			(layer "B.SilkS")
			(hide yes)
			(effects
				(font
					(size 1.27 1.27)
				)
				(justify mirror)
			)
		)
		(property "Value" ""
			(at 0 0 0)
			(layer "B.Fab")
			(effects
				(font
					(size 1.27 1.27)
				)
				(justify mirror)
			)
		)
		(duplicate_pad_numbers_are_jumpers no)
		(fp_line
			(start -0.7874 -0.4064)
			(end -0.7874 0.4064)
			(stroke
				(width 0.1524)
				(type default)
			)
			(layer "B.SilkS")
		)
		(fp_line
			(start -0.7874 0.4064)
			(end 0.7874 0.4064)
			(stroke
				(width 0.1524)
				(type default)
			)
			(layer "B.SilkS")
		)
		(fp_line
			(start 0.7874 -0.4064)
			(end -0.7874 -0.4064)
			(stroke
				(width 0.1524)
				(type default)
			)
			(layer "B.SilkS")
		)
		(fp_line
			(start 0.7874 0.4064)
			(end 0.7874 -0.4064)
			(stroke
				(width 0.1524)
				(type default)
			)
			(layer "B.SilkS")
		)
		(fp_line
			(start -0.67945 -0.3048)
			(end -0.67945 0.3048)
			(stroke
				(width 0.1)
				(type default)
			)
			(layer "B.Fab")
		)
		(fp_line
			(start -0.67945 0.3048)
			(end -0.120396 0.3048)
			(stroke
				(width 0.1)
				(type default)
			)
			(layer "B.Fab")
		)
		(fp_line
			(start -0.12065 -0.3048)
			(end -0.67945 -0.3048)
			(stroke
				(width 0.1)
				(type default)
			)
			(layer "B.Fab")
		)
		(fp_line
			(start -0.12065 -0.2794)
			(end -0.12065 -0.3048)
			(stroke
				(width 0.1)
				(type default)
			)
			(layer "B.Fab")
		)
		(fp_line
			(start -0.120396 0.2794)
			(end 0.12065 0.2794)
			(stroke
				(width 0.1)
				(type default)
			)
			(layer "B.Fab")
		)
		(fp_line
			(start -0.120396 0.3048)
			(end -0.120396 0.2794)
			(stroke
				(width 0.1)
				(type default)
			)
			(layer "B.Fab")
		)
		(fp_line
			(start 0.12065 -0.305054)
			(end 0.12065 -0.2794)
			(stroke
				(width 0.1)
				(type default)
			)
			(layer "B.Fab")
		)
		(fp_line
			(start 0.12065 -0.2794)
			(end -0.12065 -0.2794)
			(stroke
				(width 0.1)
				(type default)
			)
			(layer "B.Fab")
		)
		(fp_line
			(start 0.12065 0.2794)
			(end 0.12065 0.3048)
			(stroke
				(width 0.1)
				(type default)
			)
			(layer "B.Fab")
		)
		(fp_line
			(start 0.12065 0.3048)
			(end 0.67945 0.3048)
			(stroke
				(width 0.1)
				(type default)
			)
			(layer "B.Fab")
		)
		(fp_line
			(start 0.67945 -0.305054)
			(end 0.12065 -0.305054)
			(stroke
				(width 0.1)
				(type default)
			)
			(layer "B.Fab")
		)
		(fp_line
			(start 0.67945 0.3048)
			(end 0.67945 -0.305054)
			(stroke
				(width 0.1)
				(type default)
			)
			(layer "B.Fab")
		)
		(pad "1" smd circle
			(at 0.40005 0 180)
			(size 0 0)
			(layers "B.Cu" "B.Mask" "B.Paste")
			(net "P3V3_AUX")
		)
		(pad "2" smd circle
			(at -0.40005 0 180)
			(size 0 0)
			(layers "B.Cu" "B.Mask" "B.Paste")
			(net "GND")
		)
	)
	(footprint ""
		(layer "B.Cu")
		(at 185.166 -363.2581)
		(property "Reference" "PC7003"
			(at 0 0 0)
			(layer "B.SilkS")
			(hide yes)
			(effects
				(font
					(size 1.27 1.27)
				)
				(justify mirror)
			)
		)
		(property "Value" ""
			(at 0 0 0)
			(layer "B.Fab")
			(effects
				(font
					(size 1.27 1.27)
				)
				(justify mirror)
			)
		)
		(duplicate_pad_numbers_are_jumpers no)
		(fp_line
			(start -1.524 -0.762)
			(end -1.524 0.762)
			(stroke
				(width 0.1524)
				(type default)
			)
			(layer "B.SilkS")
		)
		(fp_line
			(start -1.524 0.762)
			(end 1.524 0.762)
			(stroke
				(width 0.1524)
				(type default)
			)
			(layer "B.SilkS")
		)
		(fp_line
			(start 1.524 -0.762)
			(end -1.524 -0.762)
			(stroke
				(width 0.1524)
				(type default)
			)
			(layer "B.SilkS")
		)
		(fp_line
			(start 1.524 0.762)
			(end 1.524 -0.762)
			(stroke
				(width 0.1524)
				(type default)
			)
			(layer "B.SilkS")
		)
		(fp_line
			(start -1.1049 -0.724916)
			(end 1.1049 -0.724916)
			(stroke
				(width 0.1)
				(type default)
			)
			(layer "B.Fab")
		)
		(fp_line
			(start -1.1049 0.724916)
			(end -1.1049 -0.724916)
			(stroke
				(width 0.1)
				(type default)
			)
			(layer "B.Fab")
		)
		(fp_line
			(start 1.1049 -0.724916)
			(end 1.1049 0.724916)
			(stroke
				(width 0.1)
				(type default)
			)
			(layer "B.Fab")
		)
		(fp_line
			(start 1.1049 0.724916)
			(end -1.1049 0.724916)
			(stroke
				(width 0.1)
				(type default)
			)
			(layer "B.Fab")
		)
		(pad "1" smd rect
			(at 0.889 0)
			(size 1.016 1.27)
			(layers "B.Cu" "B.Mask" "B.Paste")
			(net "SW_P12V_AUX_PVDD11_S3_P1_FLT")
		)
		(pad "2" smd rect
			(at -0.889 0)
			(size 1.016 1.27)
			(layers "B.Cu" "B.Mask" "B.Paste")
			(net "GND")
		)
	)
	(footprint ""
		(layer "B.Cu")
		(at 289.042856 -427.359572)
		(property "Reference" "C1708"
			(at 0 0 0)
			(layer "B.SilkS")
			(hide yes)
			(effects
				(font
					(size 1.27 1.27)
				)
				(justify mirror)
			)
		)
		(property "Value" ""
			(at 0 0 0)
			(layer "B.Fab")
			(effects
				(font
					(size 1.27 1.27)
				)
				(justify mirror)
			)
		)
		(duplicate_pad_numbers_are_jumpers no)
		(fp_line
			(start -0.7874 -0.4064)
			(end -0.7874 0.4064)
			(stroke
				(width 0.1524)
				(type default)
			)
			(layer "B.SilkS")
		)
		(fp_line
			(start -0.7874 0.4064)
			(end 0.7874 0.4064)
			(stroke
				(width 0.1524)
				(type default)
			)
			(layer "B.SilkS")
		)
		(fp_line
			(start 0.7874 -0.4064)
			(end -0.7874 -0.4064)
			(stroke
				(width 0.1524)
				(type default)
			)
			(layer "B.SilkS")
		)
		(fp_line
			(start 0.7874 0.4064)
			(end 0.7874 -0.4064)
			(stroke
				(width 0.1524)
				(type default)
			)
			(layer "B.SilkS")
		)
		(fp_line
			(start -0.67945 -0.3048)
			(end -0.67945 0.3048)
			(stroke
				(width 0.1)
				(type default)
			)
			(layer "B.Fab")
		)
		(fp_line
			(start -0.67945 0.3048)
			(end -0.120396 0.3048)
			(stroke
				(width 0.1)
				(type default)
			)
			(layer "B.Fab")
		)
		(fp_line
			(start -0.12065 -0.3048)
			(end -0.67945 -0.3048)
			(stroke
				(width 0.1)
				(type default)
			)
			(layer "B.Fab")
		)
		(fp_line
			(start -0.12065 -0.2794)
			(end -0.12065 -0.3048)
			(stroke
				(width 0.1)
				(type default)
			)
			(layer "B.Fab")
		)
		(fp_line
			(start -0.120396 0.2794)
			(end 0.12065 0.2794)
			(stroke
				(width 0.1)
				(type default)
			)
			(layer "B.Fab")
		)
		(fp_line
			(start -0.120396 0.3048)
			(end -0.120396 0.2794)
			(stroke
				(width 0.1)
				(type default)
			)
			(layer "B.Fab")
		)
		(fp_line
			(start 0.12065 -0.305054)
			(end 0.12065 -0.2794)
			(stroke
				(width 0.1)
				(type default)
			)
			(layer "B.Fab")
		)
		(fp_line
			(start 0.12065 -0.2794)
			(end -0.12065 -0.2794)
			(stroke
				(width 0.1)
				(type default)
			)
			(layer "B.Fab")
		)
		(fp_line
			(start 0.12065 0.2794)
			(end 0.12065 0.3048)
			(stroke
				(width 0.1)
				(type default)
			)
			(layer "B.Fab")
		)
		(fp_line
			(start 0.12065 0.3048)
			(end 0.67945 0.3048)
			(stroke
				(width 0.1)
				(type default)
			)
			(layer "B.Fab")
		)
		(fp_line
			(start 0.67945 -0.305054)
			(end 0.12065 -0.305054)
			(stroke
				(width 0.1)
				(type default)
			)
			(layer "B.Fab")
		)
		(fp_line
			(start 0.67945 0.3048)
			(end 0.67945 -0.305054)
			(stroke
				(width 0.1)
				(type default)
			)
			(layer "B.Fab")
		)
		(pad "1" smd circle
			(at 0.40005 0 180)
			(size 0 0)
			(layers "B.Cu" "B.Mask" "B.Paste")
			(net "P3V3_AUX")
		)
		(pad "2" smd circle
			(at -0.40005 0 180)
			(size 0 0)
			(layers "B.Cu" "B.Mask" "B.Paste")
			(net "GND")
		)
	)
)
